(kicad_pcb
	(version 20260206)
	(generator "pcbnew")
	(generator_version "10.0")
	(general
		(thickness 1.6)
		(legacy_teardrops no)
	)
	(paper "A4")
	(title_block
		(title "Bryce Canyon_IOM_IOC_16318-2_OCP.brd")
		(comment 1 "Bryce Canyon / footprints 1561-1567 of 1605")
	)
	(layers
		(0 "F.Cu" signal "TOP")
		(4 "In1.Cu" signal "L2GND")
		(6 "In2.Cu" signal "L3")
		(8 "In3.Cu" signal "L4VCC")
		(10 "In4.Cu" signal "L5VCC")
		(12 "In5.Cu" signal "L6")
		(14 "In6.Cu" signal "L7GND")
		(2 "B.Cu" signal "BOTTOM")
		(9 "F.Adhes" user "F.Adhesive")
		(11 "B.Adhes" user "B.Adhesive")
		(13 "F.Paste" user "Package Geometry/Pastemask Top")
		(15 "B.Paste" user "Package Geometry/Pastemask Bottom")
		(5 "F.SilkS" user "Ref Des/Silkscreen Top")
		(7 "B.SilkS" user "Ref Des/Silkscreen Bottom")
		(1 "F.Mask" user "Board Geometry/Soldermask Top")
		(3 "B.Mask" user "Board Geometry/Soldermask Bottom")
		(17 "Dwgs.User" user "User.Drawings")
		(19 "Cmts.User" user "User.Comments")
		(21 "Eco1.User" user "User.Eco1")
		(23 "Eco2.User" user "User.Eco2")
		(25 "Edge.Cuts" user "Board Geometry/Outline")
		(27 "Margin" user)
		(31 "F.CrtYd" user "Package Geometry/Place Bound Top")
		(29 "B.CrtYd" user "Package Geometry/Place Bound Bottom")
		(35 "F.Fab" user "Ref Des/Assembly Top")
		(33 "B.Fab" user "Ref Des/Assembly Bottom")
	)
	(footprint ""
		(layer "B.Cu")
		(at 35.738308 -124.678694)
		(property "Reference" "R783"
			(at 0 0 0)
			(layer "B.SilkS")
			(hide yes)
			(effects
				(font
					(size 1.27 1.27)
				)
				(justify mirror)
			)
		)
		(property "Value" "10KR2F-2-GP"
			(at -0.064008 -3.993896 0)
			(unlocked yes)
			(layer "B.Fab")
			(hide yes)
			(effects
				(font
					(size 1.016 1.016)
					(thickness 0.1524)
				)
				(justify mirror)
			)
		)
		(property "Device Type" "R402H16"
			(at -0.064008 -5.517896 0)
			(unlocked yes)
			(layer "B.Fab")
			(hide yes)
			(effects
				(font
					(size 1.016 1.016)
					(thickness 0.1524)
				)
				(justify mirror)
			)
		)
		(duplicate_pad_numbers_are_jumpers no)
		(fp_line
			(start -0.508 -0.9398)
			(end 0.508 -0.9398)
			(stroke
				(width 0.1524)
				(type default)
			)
			(layer "B.SilkS")
		)
		(fp_line
			(start 0.508 -0.9398)
			(end 0.508 0.9398)
			(stroke
				(width 0.1524)
				(type default)
			)
			(layer "B.SilkS")
		)
		(fp_rect
			(start 0.508 0.9398)
			(end -0.508 -0.9398)
			(stroke
				(width 0)
				(type default)
			)
			(fill no)
			(layer "B.CrtYd")
		)
		(fp_rect
			(start 0.508 0.9398)
			(end -0.508 -0.9398)
			(stroke
				(width 0)
				(type default)
			)
			(fill no)
			(layer "B.Fab")
		)
		(pad "1" smd custom
			(at 0 -0.4445 180)
			(size 0.1397 0.1397)
			(layers "B.Cu" "B.Mask" "B.Paste")
			(net "P3V3_STBY")
			(options
				(clearance outline)
				(anchor circle)
			)
			(primitives
				(gr_poly
					(pts
						(arc
							(start -0.1778 0.2794)
							(mid -0.249642 0.249642)
							(end -0.2794 0.1778)
						)
						(arc
							(start -0.2794 -0.1778)
							(mid -0.249642 -0.249642)
							(end -0.1778 -0.2794)
						)
						(arc
							(start 0.1778 -0.2794)
							(mid 0.249642 -0.249642)
							(end 0.2794 -0.1778)
						)
						(arc
							(start 0.2794 0.1778)
							(mid 0.249642 0.249642)
							(end 0.1778 0.2794)
						)
					)
					(width 0)
					(fill yes)
				)
			)
		)
		(pad "2" smd custom
			(at 0 0.4445 180)
			(size 0.1397 0.1397)
			(layers "B.Cu" "B.Mask" "B.Paste")
			(net "SYS_RESET_N_OUT")
			(options
				(clearance outline)
				(anchor circle)
			)
			(primitives
				(gr_poly
					(pts
						(arc
							(start -0.1778 0.2794)
							(mid -0.249642 0.249642)
							(end -0.2794 0.1778)
						)
						(arc
							(start -0.2794 -0.1778)
							(mid -0.249642 -0.249642)
							(end -0.1778 -0.2794)
						)
						(arc
							(start 0.1778 -0.2794)
							(mid 0.249642 -0.249642)
							(end 0.2794 -0.1778)
						)
						(arc
							(start 0.2794 0.1778)
							(mid 0.249642 0.249642)
							(end 0.1778 0.2794)
						)
					)
					(width 0)
					(fill yes)
				)
			)
		)
	)
	(footprint ""
		(layer "B.Cu")
		(at 37.228018 -143.050514)
		(property "Reference" "C59"
			(at 0 0 0)
			(layer "B.SilkS")
			(hide yes)
			(effects
				(font
					(size 1.27 1.27)
				)
				(justify mirror)
			)
		)
		(property "Value" "SC1U16V3KX-5GP"
			(at 0 -2.8194 0)
			(unlocked yes)
			(layer "B.Fab")
			(hide yes)
			(effects
				(font
					(size 1.016 1.016)
					(thickness 0.1524)
				)
				(justify mirror)
			)
		)
		(property "Device Type" "C603H36"
			(at 0 -4.3434 0)
			(unlocked yes)
			(layer "B.Fab")
			(hide yes)
			(effects
				(font
					(size 1.016 1.016)
					(thickness 0.1524)
				)
				(justify mirror)
			)
		)
		(duplicate_pad_numbers_are_jumpers no)
		(fp_line
			(start -0.508 0)
			(end 0.508 0)
			(stroke
				(width 0.2032)
				(type default)
			)
			(layer "B.SilkS")
		)
		(fp_rect
			(start 0.5842 1.3335)
			(end -0.5842 -1.3335)
			(stroke
				(width 0)
				(type default)
			)
			(fill no)
			(layer "B.CrtYd")
		)
		(fp_rect
			(start 0.5842 1.3335)
			(end -0.5842 -1.3335)
			(stroke
				(width 0)
				(type default)
			)
			(fill no)
			(layer "B.Fab")
		)
		(pad "1" smd custom
			(at 0 -0.762 180)
			(size 0.2159 0.2159)
			(layers "B.Cu" "B.Mask" "B.Paste")
			(net "P1V2_STBY")
			(options
				(clearance outline)
				(anchor circle)
			)
			(primitives
				(gr_poly
					(pts
						(arc
							(start -0.3302 0.4318)
							(mid -0.402042 0.402042)
							(end -0.4318 0.3302)
						)
						(arc
							(start -0.4318 -0.3302)
							(mid -0.402042 -0.402042)
							(end -0.3302 -0.4318)
						)
						(arc
							(start 0.3302 -0.4318)
							(mid 0.402042 -0.402042)
							(end 0.4318 -0.3302)
						)
						(arc
							(start 0.4318 0.3302)
							(mid 0.402042 0.402042)
							(end 0.3302 0.4318)
						)
					)
					(width 0)
					(fill yes)
				)
			)
		)
		(pad "2" smd custom
			(at 0 0.762 180)
			(size 0.2159 0.2159)
			(layers "B.Cu" "B.Mask" "B.Paste")
			(net "GND")
			(options
				(clearance outline)
				(anchor circle)
			)
			(primitives
				(gr_poly
					(pts
						(arc
							(start -0.3302 0.4318)
							(mid -0.402042 0.402042)
							(end -0.4318 0.3302)
						)
						(arc
							(start -0.4318 -0.3302)
							(mid -0.402042 -0.402042)
							(end -0.3302 -0.4318)
						)
						(arc
							(start 0.3302 -0.4318)
							(mid 0.402042 -0.402042)
							(end 0.4318 -0.3302)
						)
						(arc
							(start 0.4318 0.3302)
							(mid 0.402042 0.402042)
							(end 0.3302 0.4318)
						)
					)
					(width 0)
					(fill yes)
				)
			)
		)
	)
	(footprint ""
		(layer "B.Cu")
		(at 197.5612 -53.0098 -90)
		(property "Reference" "C348"
			(at 0 0 90)
			(layer "B.SilkS")
			(hide yes)
			(effects
				(font
					(size 1.27 1.27)
				)
				(justify mirror)
			)
		)
		(property "Value" "SC1U6D3V1MX-GP"
			(at -1.9177 2.0193 270)
			(unlocked yes)
			(layer "B.Fab")
			(hide yes)
			(effects
				(font
					(size 1.016 1.016)
					(thickness 0.1524)
				)
				(justify mirror)
			)
		)
		(property "Device Type" "C0201H14"
			(at -1.9177 0.4953 270)
			(unlocked yes)
			(layer "B.Fab")
			(hide yes)
			(effects
				(font
					(size 1.016 1.016)
					(thickness 0.1524)
				)
				(justify mirror)
			)
		)
		(duplicate_pad_numbers_are_jumpers no)
		(fp_rect
			(start 0.1524 0.3048)
			(end -0.1524 -0.3048)
			(stroke
				(width 0)
				(type default)
			)
			(fill no)
			(layer "B.CrtYd")
		)
		(fp_poly
			(pts
				(xy 0.2794 0.6477) (xy 0.2794 -0.6477) (xy -0.2794 -0.6477) (xy -0.2794 -0.1905) (xy -0.1524 -0.1905)
				(xy -0.1524 -0.3048) (xy 0.1524 -0.3048) (xy 0.1524 0.3048) (xy -0.1524 0.3048) (xy -0.1524 -0.1778)
				(xy -0.2794 -0.1778) (xy -0.2794 0.6477)
			)
			(stroke
				(width 0)
				(type default)
			)
			(fill no)
			(layer "B.CrtYd")
		)
		(fp_rect
			(start 0.2794 0.6477)
			(end -0.2794 -0.6477)
			(stroke
				(width 0)
				(type default)
			)
			(fill no)
			(layer "B.Fab")
		)
		(pad "1" smd custom
			(at 0 -0.2794 90)
			(size 0.0762 0.0762)
			(layers "B.Cu" "B.Mask" "B.Paste")
			(net "VDDA_SAS_REF_CLK")
			(options
				(clearance outline)
				(anchor circle)
			)
			(primitives
				(gr_poly
					(pts
						(arc
							(start 0.1524 0.127)
							(mid 0.137521 0.162921)
							(end 0.1016 0.1778)
						)
						(arc
							(start -0.1016 0.1778)
							(mid -0.137521 0.162921)
							(end -0.1524 0.127)
						)
						(arc
							(start -0.1524 -0.127)
							(mid -0.137521 -0.162921)
							(end -0.1016 -0.1778)
						)
						(arc
							(start 0.1016 -0.1778)
							(mid 0.137521 -0.162921)
							(end 0.1524 -0.127)
						)
					)
					(width 0)
					(fill yes)
				)
			)
		)
		(pad "2" smd custom
			(at 0 0.2794 90)
			(size 0.0762 0.0762)
			(layers "B.Cu" "B.Mask" "B.Paste")
			(net "GND")
			(options
				(clearance outline)
				(anchor circle)
			)
			(primitives
				(gr_poly
					(pts
						(arc
							(start 0.1524 0.127)
							(mid 0.137521 0.162921)
							(end 0.1016 0.1778)
						)
						(arc
							(start -0.1016 0.1778)
							(mid -0.137521 0.162921)
							(end -0.1524 0.127)
						)
						(arc
							(start -0.1524 -0.127)
							(mid -0.137521 -0.162921)
							(end -0.1016 -0.1778)
						)
						(arc
							(start 0.1016 -0.1778)
							(mid 0.137521 -0.162921)
							(end 0.1524 -0.127)
						)
					)
					(width 0)
					(fill yes)
				)
			)
		)
	)
	(footprint ""
		(layer "B.Cu")
		(at 82.511392 -48.766476 -90)
		(property "Reference" "C25"
			(at 0 0 90)
			(layer "B.SilkS")
			(hide yes)
			(effects
				(font
					(size 1.27 1.27)
				)
				(justify mirror)
			)
		)
		(property "Value" "SC2D2U25V5KX-2-GP"
			(at 0.0762 -6.1214 270)
			(unlocked yes)
			(layer "B.Fab")
			(hide yes)
			(effects
				(font
					(size 1.016 1.016)
					(thickness 0.1524)
				)
				(justify mirror)
			)
		)
		(property "Device Type" "C805H54"
			(at 0.0762 -8.1534 270)
			(unlocked yes)
			(layer "B.Fab")
			(hide yes)
			(effects
				(font
					(size 1.016 1.016)
					(thickness 0.1524)
				)
				(justify mirror)
			)
		)
		(duplicate_pad_numbers_are_jumpers no)
		(fp_line
			(start -0.635 0)
			(end 0.635 0)
			(stroke
				(width 0.508)
				(type default)
			)
			(layer "B.SilkS")
		)
		(fp_rect
			(start 0.9652 1.778)
			(end -0.9652 -1.778)
			(stroke
				(width 0)
				(type default)
			)
			(fill no)
			(layer "B.CrtYd")
		)
		(fp_poly
			(pts
				(xy 0.9652 -1.778) (xy -0.9652 -1.778) (xy -0.9652 1.778) (xy 0.9652 1.778)
			)
			(stroke
				(width 0)
				(type default)
			)
			(fill no)
			(layer "B.Fab")
		)
		(pad "1" smd rect
			(at 0 -0.9652 90)
			(size 1.397 1.143)
			(layers "B.Cu" "B.Mask" "B.Paste")
			(net "P5V_STBY")
		)
		(pad "2" smd rect
			(at 0 0.9652 90)
			(size 1.397 1.143)
			(layers "B.Cu" "B.Mask" "B.Paste")
			(net "GND")
		)
	)
	(footprint ""
		(layer "B.Cu")
		(at 207.7974 -56.9468 180)
		(property "Reference" "R592"
			(at 0 0 0)
			(layer "B.SilkS")
			(hide yes)
			(effects
				(font
					(size 1.27 1.27)
				)
				(justify mirror)
			)
		)
		(property "Value" "2K2R2F-GP"
			(at -0.064008 -3.993896 180)
			(unlocked yes)
			(layer "B.Fab")
			(hide yes)
			(effects
				(font
					(size 1.016 1.016)
					(thickness 0.1524)
				)
				(justify mirror)
			)
		)
		(property "Device Type" "R402H16"
			(at -0.064008 -5.517896 180)
			(unlocked yes)
			(layer "B.Fab")
			(hide yes)
			(effects
				(font
					(size 1.016 1.016)
					(thickness 0.1524)
				)
				(justify mirror)
			)
		)
		(duplicate_pad_numbers_are_jumpers no)
		(fp_line
			(start 0.508 -0.9398)
			(end 0.508 0.9398)
			(stroke
				(width 0.1524)
				(type default)
			)
			(layer "B.SilkS")
		)
		(fp_line
			(start -0.508 -0.9398)
			(end 0.508 -0.9398)
			(stroke
				(width 0.1524)
				(type default)
			)
			(layer "B.SilkS")
		)
		(fp_rect
			(start 0.508 0.9398)
			(end -0.508 -0.9398)
			(stroke
				(width 0)
				(type default)
			)
			(fill no)
			(layer "B.CrtYd")
		)
		(fp_rect
			(start 0.508 0.9398)
			(end -0.508 -0.9398)
			(stroke
				(width 0)
				(type default)
			)
			(fill no)
			(layer "B.Fab")
		)
		(pad "1" smd custom
			(at 0 -0.4445)
			(size 0.1397 0.1397)
			(layers "B.Cu" "B.Mask" "B.Paste")
			(net "P1V8")
			(options
				(clearance outline)
				(anchor circle)
			)
			(primitives
				(gr_poly
					(pts
						(arc
							(start -0.1778 0.2794)
							(mid -0.249642 0.249642)
							(end -0.2794 0.1778)
						)
						(arc
							(start -0.2794 -0.1778)
							(mid -0.249642 -0.249642)
							(end -0.1778 -0.2794)
						)
						(arc
							(start 0.1778 -0.2794)
							(mid 0.249642 -0.249642)
							(end 0.2794 -0.1778)
						)
						(arc
							(start 0.2794 0.1778)
							(mid 0.249642 0.249642)
							(end 0.1778 0.2794)
						)
					)
					(width 0)
					(fill yes)
				)
			)
		)
		(pad "2" smd custom
			(at 0 0.4445)
			(size 0.1397 0.1397)
			(layers "B.Cu" "B.Mask" "B.Paste")
			(net "SIO_CLK_1")
			(options
				(clearance outline)
				(anchor circle)
			)
			(primitives
				(gr_poly
					(pts
						(arc
							(start -0.1778 0.2794)
							(mid -0.249642 0.249642)
							(end -0.2794 0.1778)
						)
						(arc
							(start -0.2794 -0.1778)
							(mid -0.249642 -0.249642)
							(end -0.1778 -0.2794)
						)
						(arc
							(start 0.1778 -0.2794)
							(mid 0.249642 -0.249642)
							(end 0.2794 -0.1778)
						)
						(arc
							(start 0.2794 0.1778)
							(mid 0.249642 0.249642)
							(end 0.1778 0.2794)
						)
					)
					(width 0)
					(fill yes)
				)
			)
		)
	)
	(footprint ""
		(layer "B.Cu")
		(at 184.13476 -63.4619 90)
		(property "Reference" "C476"
			(at 0 0 90)
			(layer "B.SilkS")
			(hide yes)
			(effects
				(font
					(size 1.27 1.27)
				)
				(justify mirror)
			)
		)
		(property "Value" "SC1KP50V2KX-1GP"
			(at -1.1811 -2.7051 90)
			(unlocked yes)
			(layer "B.Fab")
			(hide yes)
			(effects
				(font
					(size 1.016 1.016)
					(thickness 0.1524)
				)
				(justify mirror)
			)
		)
		(property "Device Type" "C402H22"
			(at -1.1811 -4.2291 90)
			(unlocked yes)
			(layer "B.Fab")
			(hide yes)
			(effects
				(font
					(size 1.016 1.016)
					(thickness 0.1524)
				)
				(justify mirror)
			)
		)
		(duplicate_pad_numbers_are_jumpers no)
		(fp_rect
			(start 0.4318 0.9525)
			(end -0.4318 -0.9525)
			(stroke
				(width 0)
				(type default)
			)
			(fill no)
			(layer "B.CrtYd")
		)
		(fp_rect
			(start 0.4318 0.9525)
			(end -0.4318 -0.9525)
			(stroke
				(width 0)
				(type default)
			)
			(fill no)
			(layer "B.Fab")
		)
		(pad "1" smd custom
			(at 0 -0.4445 270)
			(size 0.1524 0.1524)
			(layers "B.Cu" "B.Mask" "B.Paste")
			(net "P1V8")
			(options
				(clearance outline)
				(anchor circle)
			)
			(primitives
				(gr_poly
					(pts
						(arc
							(start 0.3048 0.2032)
							(mid 0.275042 0.275042)
							(end 0.2032 0.3048)
						)
						(arc
							(start -0.2032 0.3048)
							(mid -0.275042 0.275042)
							(end -0.3048 0.2032)
						)
						(arc
							(start -0.3048 -0.2032)
							(mid -0.275042 -0.275042)
							(end -0.2032 -0.3048)
						)
						(arc
							(start 0.2032 -0.3048)
							(mid 0.275042 -0.275042)
							(end 0.3048 -0.2032)
						)
					)
					(width 0)
					(fill yes)
				)
			)
		)
		(pad "2" smd custom
			(at 0 0.4445 270)
			(size 0.1524 0.1524)
			(layers "B.Cu" "B.Mask" "B.Paste")
			(net "GND")
			(options
				(clearance outline)
				(anchor circle)
			)
			(primitives
				(gr_poly
					(pts
						(arc
							(start 0.3048 0.2032)
							(mid 0.275042 0.275042)
							(end 0.2032 0.3048)
						)
						(arc
							(start -0.2032 0.3048)
							(mid -0.275042 0.275042)
							(end -0.3048 0.2032)
						)
						(arc
							(start -0.3048 -0.2032)
							(mid -0.275042 -0.275042)
							(end -0.2032 -0.3048)
						)
						(arc
							(start 0.2032 -0.3048)
							(mid 0.275042 -0.275042)
							(end 0.3048 -0.2032)
						)
					)
					(width 0)
					(fill yes)
				)
			)
		)
	)
	(footprint ""
		(layer "B.Cu")
		(at 44.061888 -119.876062 90)
		(property "Reference" "U27"
			(at 0 0 90)
			(layer "B.SilkS")
			(hide yes)
			(effects
				(font
					(size 1.27 1.27)
				)
				(justify mirror)
			)
		)
		(property "Value" "TMP75AIDGKR-GP"
			(at 0.1143 -9.1948 90)
			(unlocked yes)
			(layer "B.Fab")
			(hide yes)
			(effects
				(font
					(size 1.016 1.016)
					(thickness 0.1524)
				)
				(justify mirror)
			)
		)
		(property "Device Type" "MSOP8-1H44"
			(at 0.1143 -10.795 90)
			(unlocked yes)
			(layer "B.Fab")
			(hide yes)
			(effects
				(font
					(size 1.016 1.016)
					(thickness 0.1524)
				)
				(justify mirror)
			)
		)
		(duplicate_pad_numbers_are_jumpers no)
		(fp_line
			(start 1.9558 -1.016)
			(end 1.9558 1.016)
			(stroke
				(width 0.1524)
				(type default)
			)
			(layer "B.SilkS")
		)
		(fp_line
			(start -1.0795 -1.016)
			(end 1.9558 -1.016)
			(stroke
				(width 0.1524)
				(type default)
			)
			(layer "B.SilkS")
		)
		(fp_line
			(start 1.9558 -0.5461)
			(end 1.4478 -0.0381)
			(stroke
				(width 0.1524)
				(type default)
			)
			(layer "B.SilkS")
		)
		(fp_line
			(start 1.4478 -0.0381)
			(end 1.9558 0.4699)
			(stroke
				(width 0.1524)
				(type default)
			)
			(layer "B.SilkS")
		)
		(fp_line
			(start 1.9558 1.016)
			(end -1.0795 1.016)
			(stroke
				(width 0.1524)
				(type default)
			)
			(layer "B.SilkS")
		)
		(fp_line
			(start -1.0795 1.016)
			(end -1.0795 -1.016)
			(stroke
				(width 0.1524)
				(type default)
			)
			(layer "B.SilkS")
		)
		(fp_line
			(start 1.778 1.0922)
			(end 1.778 3.048)
			(stroke
				(width 0.508)
				(type default)
			)
			(layer "B.SilkS")
		)
		(fp_poly
			(pts
				(xy 1.1557 -1.016) (xy 1.1557 1.016) (xy -1.1557 1.016) (xy -1.1557 -1.016)
			)
			(stroke
				(width 0)
				(type default)
			)
			(fill yes)
			(layer "B.SilkS")
		)
		(fp_rect
			(start 1.4986 2.4511)
			(end -1.4986 -2.4511)
			(stroke
				(width 0)
				(type default)
			)
			(fill no)
			(layer "B.CrtYd")
		)
		(fp_poly
			(pts
				(xy 2.032 3.302) (xy 2.032 -3.302) (xy -2.032 -3.302) (xy -2.032 -2.1209) (xy -1.4986 -2.1209) (xy -1.4986 -2.4511)
				(xy 1.4986 -2.4511) (xy 1.4986 2.4511) (xy -1.4986 2.4511) (xy -1.4986 -2.1082) (xy -2.032 -2.1082)
				(xy -2.032 3.302)
			)
			(stroke
				(width 0)
				(type default)
			)
			(fill no)
			(layer "B.CrtYd")
		)
		(fp_rect
			(start 2.032 3.302)
			(end -2.032 -3.302)
			(stroke
				(width 0)
				(type default)
			)
			(fill no)
			(layer "B.Fab")
		)
		(pad "1" smd rect
			(at 0.97536 2.05486 270)
			(size 0.3556 1.524)
			(layers "B.Cu" "B.Mask" "B.Paste")
			(net "TEMP_3_SDA")
		)
		(pad "2" smd rect
			(at 0.32512 2.05486 270)
			(size 0.3556 1.524)
			(layers "B.Cu" "B.Mask" "B.Paste")
			(net "TEMP_3_SCL")
		)
		(pad "3" smd rect
			(at -0.32512 2.05486 270)
			(size 0.3556 1.524)
			(layers "B.Cu" "B.Mask" "B.Paste")
			(net "TEMP_3_ALERT")
		)
		(pad "4" smd rect
			(at -0.97536 2.05486 270)
			(size 0.3556 1.524)
			(layers "B.Cu" "B.Mask" "B.Paste")
			(net "GND")
		)
		(pad "5" smd rect
			(at -0.97536 -2.05486 270)
			(size 0.3556 1.524)
			(layers "B.Cu" "B.Mask" "B.Paste")
			(net "TEMP_3_A2")
		)
		(pad "6" smd rect
			(at -0.32512 -2.05486 270)
			(size 0.3556 1.524)
			(layers "B.Cu" "B.Mask" "B.Paste")
			(net "TEMP_3_A1")
		)
		(pad "7" smd rect
			(at 0.32512 -2.05486 270)
			(size 0.3556 1.524)
			(layers "B.Cu" "B.Mask" "B.Paste")
			(net "TEMP_3_A0")
		)
		(pad "8" smd rect
			(at 0.97536 -2.05486 270)
			(size 0.3556 1.524)
			(layers "B.Cu" "B.Mask" "B.Paste")
			(net "P3V3_STBY")
		)
	)
)
